FILE_TYPE = CONNECTIVITY;
{Allegro Design Entry HDL 16.5-S008 (v16-5-13Y) 10/18/2011}
"PAGE_NUMBER" = 1;
0"NC";
1"G\I";
2"P5V \G";
%"SYNONYM"
"1","(1850,2050)","0","mstr_standard","4P";
;
NEEDS_NO_SIZE"TRUE"
BODY_TYPE"PLUMBING"
CDS_LIB"mstr_standard";
"A\NWC\NAC"1;
"A\NWC\NAC"2;
%"DRAWING"
"2","(1275,1750)","0","mstr_standard","";
;
LAST_MODIFIED"Tue Oct 25 14:30:26 2011"
TITLE"P5V"
ABBREV"P5V";
END.
